(kicad_pcb
	(version 20260206)
	(generator "pcbnew")
	(generator_version "10.0")
	(general
		(thickness 1.6)
		(legacy_teardrops no)
	)
	(paper "A4")
	(title_block
		(title "04192023_DAF0TMB3IC0_F0TG_MB_C_brd_V02_OCP.brd")
		(comment 1 "Grand Teton / footprints 4473-4479 of 8354")
	)
	(layers
		(0 "F.Cu" signal "TOP")
		(4 "In1.Cu" signal "GND")
		(6 "In2.Cu" signal "IN1")
		(8 "In3.Cu" signal "GND1")
		(10 "In4.Cu" signal "IN2")
		(12 "In5.Cu" signal "GND2")
		(14 "In6.Cu" signal "IN3")
		(16 "In7.Cu" signal "GND3")
		(18 "In8.Cu" signal "VCC")
		(20 "In9.Cu" signal "VCC1")
		(22 "In10.Cu" signal "GND4")
		(24 "In11.Cu" signal "IN4")
		(26 "In12.Cu" signal "GND5")
		(28 "In13.Cu" signal "IN5")
		(30 "In14.Cu" signal "GND6")
		(32 "In15.Cu" signal "IN6")
		(34 "In16.Cu" signal "GND7")
		(2 "B.Cu" signal "BOTTOM")
		(9 "F.Adhes" user "F.Adhesive")
		(11 "B.Adhes" user "B.Adhesive")
		(13 "F.Paste" user "Package Geometry/Pastemask Top")
		(15 "B.Paste" user "Package Geometry/Pastemask Bottom")
		(5 "F.SilkS" user "Ref Des/Silkscreen Top")
		(7 "B.SilkS" user "Ref Des/Silkscreen Bottom")
		(1 "F.Mask" user "Board Geometry/Soldermask Top")
		(3 "B.Mask" user "Board Geometry/Soldermask Bottom")
		(17 "Dwgs.User" user "User.Drawings")
		(19 "Cmts.User" user "User.Comments")
		(21 "Eco1.User" user "User.Eco1")
		(23 "Eco2.User" user "User.Eco2")
		(25 "Edge.Cuts" user "Board Geometry/Outline")
		(27 "Margin" user)
		(31 "F.CrtYd" user "Package Geometry/Place Bound Top")
		(29 "B.CrtYd" user "Package Geometry/Place Bound Bottom")
		(35 "F.Fab" user "Ref Des/Assembly Top")
		(33 "B.Fab" user "Ref Des/Assembly Bottom")
	)
	(footprint ""
		(layer "F.Cu")
		(at 13.335 -77.089)
		(property "Reference" "C8004"
			(at 0 0 0)
			(layer "F.SilkS")
			(hide yes)
			(effects
				(font
					(size 1.27 1.27)
				)
			)
		)
		(property "Value" ""
			(at 0 0 0)
			(layer "F.Fab")
			(effects
				(font
					(size 1.27 1.27)
				)
			)
		)
		(duplicate_pad_numbers_are_jumpers no)
		(fp_line
			(start -0.7874 -0.4064)
			(end 0.7874 -0.4064)
			(stroke
				(width 0.1524)
				(type default)
			)
			(layer "F.SilkS")
		)
		(fp_line
			(start -0.7874 0.4064)
			(end -0.7874 -0.4064)
			(stroke
				(width 0.1524)
				(type default)
			)
			(layer "F.SilkS")
		)
		(fp_line
			(start 0.7874 -0.4064)
			(end 0.7874 0.4064)
			(stroke
				(width 0.1524)
				(type default)
			)
			(layer "F.SilkS")
		)
		(fp_line
			(start 0.7874 0.4064)
			(end -0.7874 0.4064)
			(stroke
				(width 0.1524)
				(type default)
			)
			(layer "F.SilkS")
		)
		(fp_line
			(start -0.67945 -0.305054)
			(end -0.12065 -0.305054)
			(stroke
				(width 0.1)
				(type default)
			)
			(layer "F.Fab")
		)
		(fp_line
			(start -0.67945 0.3048)
			(end -0.67945 -0.305054)
			(stroke
				(width 0.1)
				(type default)
			)
			(layer "F.Fab")
		)
		(fp_line
			(start -0.12065 -0.305054)
			(end -0.12065 -0.2794)
			(stroke
				(width 0.1)
				(type default)
			)
			(layer "F.Fab")
		)
		(fp_line
			(start -0.12065 -0.2794)
			(end 0.12065 -0.2794)
			(stroke
				(width 0.1)
				(type default)
			)
			(layer "F.Fab")
		)
		(fp_line
			(start -0.12065 0.2794)
			(end -0.12065 0.3048)
			(stroke
				(width 0.1)
				(type default)
			)
			(layer "F.Fab")
		)
		(fp_line
			(start -0.12065 0.3048)
			(end -0.67945 0.3048)
			(stroke
				(width 0.1)
				(type default)
			)
			(layer "F.Fab")
		)
		(fp_line
			(start 0.120396 0.2794)
			(end -0.12065 0.2794)
			(stroke
				(width 0.1)
				(type default)
			)
			(layer "F.Fab")
		)
		(fp_line
			(start 0.120396 0.3048)
			(end 0.120396 0.2794)
			(stroke
				(width 0.1)
				(type default)
			)
			(layer "F.Fab")
		)
		(fp_line
			(start 0.12065 -0.3048)
			(end 0.67945 -0.3048)
			(stroke
				(width 0.1)
				(type default)
			)
			(layer "F.Fab")
		)
		(fp_line
			(start 0.12065 -0.2794)
			(end 0.12065 -0.3048)
			(stroke
				(width 0.1)
				(type default)
			)
			(layer "F.Fab")
		)
		(fp_line
			(start 0.67945 -0.3048)
			(end 0.67945 0.3048)
			(stroke
				(width 0.1)
				(type default)
			)
			(layer "F.Fab")
		)
		(fp_line
			(start 0.67945 0.3048)
			(end 0.120396 0.3048)
			(stroke
				(width 0.1)
				(type default)
			)
			(layer "F.Fab")
		)
		(pad "1" smd circle
			(at -0.40005 0)
			(size 0 0)
			(layers "F.Cu" "F.Mask" "F.Paste")
			(net "OCP_V3_2_PRSNT23_R1_N")
		)
		(pad "2" smd circle
			(at 0.40005 0)
			(size 0 0)
			(layers "F.Cu" "F.Mask" "F.Paste")
			(net "GND")
		)
	)
	(footprint ""
		(layer "F.Cu")
		(at 108.360464 -257.750564)
		(property "Reference" "C2664"
			(at 0 0 0)
			(layer "F.SilkS")
			(hide yes)
			(effects
				(font
					(size 1.27 1.27)
				)
			)
		)
		(property "Value" ""
			(at 0 0 0)
			(layer "F.Fab")
			(effects
				(font
					(size 1.27 1.27)
				)
			)
		)
		(duplicate_pad_numbers_are_jumpers no)
		(fp_line
			(start -0.7874 -0.4064)
			(end 0.7874 -0.4064)
			(stroke
				(width 0.1524)
				(type default)
			)
			(layer "F.SilkS")
		)
		(fp_line
			(start -0.7874 0.4064)
			(end -0.7874 -0.4064)
			(stroke
				(width 0.1524)
				(type default)
			)
			(layer "F.SilkS")
		)
		(fp_line
			(start 0.7874 -0.4064)
			(end 0.7874 0.4064)
			(stroke
				(width 0.1524)
				(type default)
			)
			(layer "F.SilkS")
		)
		(fp_line
			(start 0.7874 0.4064)
			(end -0.7874 0.4064)
			(stroke
				(width 0.1524)
				(type default)
			)
			(layer "F.SilkS")
		)
		(fp_line
			(start -0.67945 -0.305054)
			(end -0.12065 -0.305054)
			(stroke
				(width 0.1)
				(type default)
			)
			(layer "F.Fab")
		)
		(fp_line
			(start -0.67945 0.3048)
			(end -0.67945 -0.305054)
			(stroke
				(width 0.1)
				(type default)
			)
			(layer "F.Fab")
		)
		(fp_line
			(start -0.12065 -0.305054)
			(end -0.12065 -0.2794)
			(stroke
				(width 0.1)
				(type default)
			)
			(layer "F.Fab")
		)
		(fp_line
			(start -0.12065 -0.2794)
			(end 0.12065 -0.2794)
			(stroke
				(width 0.1)
				(type default)
			)
			(layer "F.Fab")
		)
		(fp_line
			(start -0.12065 0.2794)
			(end -0.12065 0.3048)
			(stroke
				(width 0.1)
				(type default)
			)
			(layer "F.Fab")
		)
		(fp_line
			(start -0.12065 0.3048)
			(end -0.67945 0.3048)
			(stroke
				(width 0.1)
				(type default)
			)
			(layer "F.Fab")
		)
		(fp_line
			(start 0.120396 0.2794)
			(end -0.12065 0.2794)
			(stroke
				(width 0.1)
				(type default)
			)
			(layer "F.Fab")
		)
		(fp_line
			(start 0.120396 0.3048)
			(end 0.120396 0.2794)
			(stroke
				(width 0.1)
				(type default)
			)
			(layer "F.Fab")
		)
		(fp_line
			(start 0.12065 -0.3048)
			(end 0.67945 -0.3048)
			(stroke
				(width 0.1)
				(type default)
			)
			(layer "F.Fab")
		)
		(fp_line
			(start 0.12065 -0.2794)
			(end 0.12065 -0.3048)
			(stroke
				(width 0.1)
				(type default)
			)
			(layer "F.Fab")
		)
		(fp_line
			(start 0.67945 -0.3048)
			(end 0.67945 0.3048)
			(stroke
				(width 0.1)
				(type default)
			)
			(layer "F.Fab")
		)
		(fp_line
			(start 0.67945 0.3048)
			(end 0.120396 0.3048)
			(stroke
				(width 0.1)
				(type default)
			)
			(layer "F.Fab")
		)
		(pad "1" smd circle
			(at -0.40005 0)
			(size 0 0)
			(layers "F.Cu" "F.Mask" "F.Paste")
			(net "PVDD18_S5_P1")
		)
		(pad "2" smd circle
			(at 0.40005 0)
			(size 0 0)
			(layers "F.Cu" "F.Mask" "F.Paste")
			(net "GND")
		)
	)
	(footprint ""
		(layer "F.Cu")
		(at 124.618496 -373.03583 -90)
		(property "Reference" "C1530"
			(at 0 0 270)
			(layer "F.SilkS")
			(hide yes)
			(effects
				(font
					(size 1.27 1.27)
				)
			)
		)
		(property "Value" ""
			(at 0 0 270)
			(layer "F.Fab")
			(effects
				(font
					(size 1.27 1.27)
				)
			)
		)
		(duplicate_pad_numbers_are_jumpers no)
		(fp_line
			(start -0.299974 0.150114)
			(end -0.299974 -0.150114)
			(stroke
				(width 0.1)
				(type default)
			)
			(layer "F.Fab")
		)
		(fp_line
			(start 0.299974 0.150114)
			(end -0.299974 0.150114)
			(stroke
				(width 0.1)
				(type default)
			)
			(layer "F.Fab")
		)
		(fp_line
			(start -0.299974 -0.150114)
			(end 0.299974 -0.150114)
			(stroke
				(width 0.1)
				(type default)
			)
			(layer "F.Fab")
		)
		(fp_line
			(start 0.299974 -0.150114)
			(end 0.299974 0.150114)
			(stroke
				(width 0.1)
				(type default)
			)
			(layer "F.Fab")
		)
		(pad "1" smd rect
			(at -0.2667 0 270)
			(size 0.3048 0.381)
			(layers "F.Cu" "F.Mask" "F.Paste")
			(net "P5E_CPU1_P3_TX_C_DN<8>")
		)
		(pad "2" smd rect
			(at 0.2667 0 270)
			(size 0.3048 0.381)
			(layers "F.Cu" "F.Mask" "F.Paste")
			(net "P5E_CPU1_P3_TX_DN<8>")
		)
	)
	(footprint ""
		(layer "F.Cu")
		(at 307.213 -355.854)
		(property "Reference" "PC68"
			(at 0 0 0)
			(layer "F.SilkS")
			(hide yes)
			(effects
				(font
					(size 1.27 1.27)
				)
			)
		)
		(property "Value" ""
			(at 0 0 0)
			(layer "F.Fab")
			(effects
				(font
					(size 1.27 1.27)
				)
			)
		)
		(duplicate_pad_numbers_are_jumpers no)
		(fp_line
			(start -0.7874 -0.4064)
			(end 0.7874 -0.4064)
			(stroke
				(width 0.1524)
				(type default)
			)
			(layer "F.SilkS")
		)
		(fp_line
			(start -0.7874 0.4064)
			(end -0.7874 -0.4064)
			(stroke
				(width 0.1524)
				(type default)
			)
			(layer "F.SilkS")
		)
		(fp_line
			(start 0.7874 -0.4064)
			(end 0.7874 0.4064)
			(stroke
				(width 0.1524)
				(type default)
			)
			(layer "F.SilkS")
		)
		(fp_line
			(start 0.7874 0.4064)
			(end -0.7874 0.4064)
			(stroke
				(width 0.1524)
				(type default)
			)
			(layer "F.SilkS")
		)
		(fp_line
			(start -0.67945 -0.305054)
			(end -0.12065 -0.305054)
			(stroke
				(width 0.1)
				(type default)
			)
			(layer "F.Fab")
		)
		(fp_line
			(start -0.67945 0.3048)
			(end -0.67945 -0.305054)
			(stroke
				(width 0.1)
				(type default)
			)
			(layer "F.Fab")
		)
		(fp_line
			(start -0.12065 -0.305054)
			(end -0.12065 -0.2794)
			(stroke
				(width 0.1)
				(type default)
			)
			(layer "F.Fab")
		)
		(fp_line
			(start -0.12065 -0.2794)
			(end 0.12065 -0.2794)
			(stroke
				(width 0.1)
				(type default)
			)
			(layer "F.Fab")
		)
		(fp_line
			(start -0.12065 0.2794)
			(end -0.12065 0.3048)
			(stroke
				(width 0.1)
				(type default)
			)
			(layer "F.Fab")
		)
		(fp_line
			(start -0.12065 0.3048)
			(end -0.67945 0.3048)
			(stroke
				(width 0.1)
				(type default)
			)
			(layer "F.Fab")
		)
		(fp_line
			(start 0.120396 0.2794)
			(end -0.12065 0.2794)
			(stroke
				(width 0.1)
				(type default)
			)
			(layer "F.Fab")
		)
		(fp_line
			(start 0.120396 0.3048)
			(end 0.120396 0.2794)
			(stroke
				(width 0.1)
				(type default)
			)
			(layer "F.Fab")
		)
		(fp_line
			(start 0.12065 -0.3048)
			(end 0.67945 -0.3048)
			(stroke
				(width 0.1)
				(type default)
			)
			(layer "F.Fab")
		)
		(fp_line
			(start 0.12065 -0.2794)
			(end 0.12065 -0.3048)
			(stroke
				(width 0.1)
				(type default)
			)
			(layer "F.Fab")
		)
		(fp_line
			(start 0.67945 -0.3048)
			(end 0.67945 0.3048)
			(stroke
				(width 0.1)
				(type default)
			)
			(layer "F.Fab")
		)
		(fp_line
			(start 0.67945 0.3048)
			(end 0.120396 0.3048)
			(stroke
				(width 0.1)
				(type default)
			)
			(layer "F.Fab")
		)
		(pad "1" smd circle
			(at -0.40005 0)
			(size 0 0)
			(layers "F.Cu" "F.Mask" "F.Paste")
			(net "VSENSE_PVDDCR_CPU1_P0_VSEN0")
		)
		(pad "2" smd circle
			(at 0.40005 0)
			(size 0 0)
			(layers "F.Cu" "F.Mask" "F.Paste")
			(net "VSENSE_VSS_SENSE_C_P0")
		)
	)
	(footprint ""
		(layer "F.Cu")
		(at 217.58402 -16.381222 -90)
		(property "Reference" "R3181"
			(at 0 0 270)
			(layer "F.SilkS")
			(hide yes)
			(effects
				(font
					(size 1.27 1.27)
				)
			)
		)
		(property "Value" ""
			(at 0 0 270)
			(layer "F.Fab")
			(effects
				(font
					(size 1.27 1.27)
				)
			)
		)
		(duplicate_pad_numbers_are_jumpers no)
		(fp_line
			(start -0.7874 0.4064)
			(end -0.7874 -0.4064)
			(stroke
				(width 0.1524)
				(type default)
			)
			(layer "F.SilkS")
		)
		(fp_line
			(start 0.7874 0.4064)
			(end -0.7874 0.4064)
			(stroke
				(width 0.1524)
				(type default)
			)
			(layer "F.SilkS")
		)
		(fp_line
			(start -0.7874 -0.4064)
			(end 0.7874 -0.4064)
			(stroke
				(width 0.1524)
				(type default)
			)
			(layer "F.SilkS")
		)
		(fp_line
			(start 0.7874 -0.4064)
			(end 0.7874 0.4064)
			(stroke
				(width 0.1524)
				(type default)
			)
			(layer "F.SilkS")
		)
		(fp_line
			(start -0.67945 0.3048)
			(end -0.67945 -0.305054)
			(stroke
				(width 0.1)
				(type default)
			)
			(layer "F.Fab")
		)
		(fp_line
			(start -0.12065 0.3048)
			(end -0.67945 0.3048)
			(stroke
				(width 0.1)
				(type default)
			)
			(layer "F.Fab")
		)
		(fp_line
			(start 0.120396 0.3048)
			(end 0.120396 0.2794)
			(stroke
				(width 0.1)
				(type default)
			)
			(layer "F.Fab")
		)
		(fp_line
			(start 0.67945 0.3048)
			(end 0.120396 0.3048)
			(stroke
				(width 0.1)
				(type default)
			)
			(layer "F.Fab")
		)
		(fp_line
			(start -0.12065 0.2794)
			(end -0.12065 0.3048)
			(stroke
				(width 0.1)
				(type default)
			)
			(layer "F.Fab")
		)
		(fp_line
			(start 0.120396 0.2794)
			(end -0.12065 0.2794)
			(stroke
				(width 0.1)
				(type default)
			)
			(layer "F.Fab")
		)
		(fp_line
			(start -0.12065 -0.2794)
			(end 0.12065 -0.2794)
			(stroke
				(width 0.1)
				(type default)
			)
			(layer "F.Fab")
		)
		(fp_line
			(start 0.12065 -0.2794)
			(end 0.12065 -0.3048)
			(stroke
				(width 0.1)
				(type default)
			)
			(layer "F.Fab")
		)
		(fp_line
			(start 0.12065 -0.3048)
			(end 0.67945 -0.3048)
			(stroke
				(width 0.1)
				(type default)
			)
			(layer "F.Fab")
		)
		(fp_line
			(start 0.67945 -0.3048)
			(end 0.67945 0.3048)
			(stroke
				(width 0.1)
				(type default)
			)
			(layer "F.Fab")
		)
		(fp_line
			(start -0.67945 -0.305054)
			(end -0.12065 -0.305054)
			(stroke
				(width 0.1)
				(type default)
			)
			(layer "F.Fab")
		)
		(fp_line
			(start -0.12065 -0.305054)
			(end -0.12065 -0.2794)
			(stroke
				(width 0.1)
				(type default)
			)
			(layer "F.Fab")
		)
		(pad "1" smd circle
			(at -0.40005 0 270)
			(size 0 0)
			(layers "F.Cu" "F.Mask" "F.Paste")
			(net "CLK_50M_NCSI_OCP_2")
		)
		(pad "2" smd circle
			(at 0.40005 0 270)
			(size 0 0)
			(layers "F.Cu" "F.Mask" "F.Paste")
			(net "CLK_50M_NCSI_OCP_V3_2")
		)
	)
	(footprint ""
		(layer "F.Cu")
		(at 147.877022 -21.506942 90)
		(property "Reference" "R6071"
			(at 0 0 90)
			(layer "F.SilkS")
			(hide yes)
			(effects
				(font
					(size 1.27 1.27)
				)
			)
		)
		(property "Value" ""
			(at 0 0 90)
			(layer "F.Fab")
			(effects
				(font
					(size 1.27 1.27)
				)
			)
		)
		(duplicate_pad_numbers_are_jumpers no)
		(fp_line
			(start 0.7874 -0.4064)
			(end 0.7874 0.4064)
			(stroke
				(width 0.1524)
				(type default)
			)
			(layer "F.SilkS")
		)
		(fp_line
			(start -0.7874 -0.4064)
			(end 0.7874 -0.4064)
			(stroke
				(width 0.1524)
				(type default)
			)
			(layer "F.SilkS")
		)
		(fp_line
			(start 0.7874 0.4064)
			(end -0.7874 0.4064)
			(stroke
				(width 0.1524)
				(type default)
			)
			(layer "F.SilkS")
		)
		(fp_line
			(start -0.7874 0.4064)
			(end -0.7874 -0.4064)
			(stroke
				(width 0.1524)
				(type default)
			)
			(layer "F.SilkS")
		)
		(fp_line
			(start -0.12065 -0.305054)
			(end -0.12065 -0.2794)
			(stroke
				(width 0.1)
				(type default)
			)
			(layer "F.Fab")
		)
		(fp_line
			(start -0.67945 -0.305054)
			(end -0.12065 -0.305054)
			(stroke
				(width 0.1)
				(type default)
			)
			(layer "F.Fab")
		)
		(fp_line
			(start 0.67945 -0.3048)
			(end 0.67945 0.3048)
			(stroke
				(width 0.1)
				(type default)
			)
			(layer "F.Fab")
		)
		(fp_line
			(start 0.12065 -0.3048)
			(end 0.67945 -0.3048)
			(stroke
				(width 0.1)
				(type default)
			)
			(layer "F.Fab")
		)
		(fp_line
			(start 0.12065 -0.2794)
			(end 0.12065 -0.3048)
			(stroke
				(width 0.1)
				(type default)
			)
			(layer "F.Fab")
		)
		(fp_line
			(start -0.12065 -0.2794)
			(end 0.12065 -0.2794)
			(stroke
				(width 0.1)
				(type default)
			)
			(layer "F.Fab")
		)
		(fp_line
			(start 0.120396 0.2794)
			(end -0.12065 0.2794)
			(stroke
				(width 0.1)
				(type default)
			)
			(layer "F.Fab")
		)
		(fp_line
			(start -0.12065 0.2794)
			(end -0.12065 0.3048)
			(stroke
				(width 0.1)
				(type default)
			)
			(layer "F.Fab")
		)
		(fp_line
			(start 0.67945 0.3048)
			(end 0.120396 0.3048)
			(stroke
				(width 0.1)
				(type default)
			)
			(layer "F.Fab")
		)
		(fp_line
			(start 0.120396 0.3048)
			(end 0.120396 0.2794)
			(stroke
				(width 0.1)
				(type default)
			)
			(layer "F.Fab")
		)
		(fp_line
			(start -0.12065 0.3048)
			(end -0.67945 0.3048)
			(stroke
				(width 0.1)
				(type default)
			)
			(layer "F.Fab")
		)
		(fp_line
			(start -0.67945 0.3048)
			(end -0.67945 -0.305054)
			(stroke
				(width 0.1)
				(type default)
			)
			(layer "F.Fab")
		)
		(pad "1" smd circle
			(at -0.40005 0 90)
			(size 0 0)
			(layers "F.Cu" "F.Mask" "F.Paste")
			(net "P3V3_AUX")
		)
		(pad "2" smd circle
			(at 0.40005 0 90)
			(size 0 0)
			(layers "F.Cu" "F.Mask" "F.Paste")
			(net "PU_JTAG_DBP_BMC_PRDY_N")
		)
	)
	(footprint ""
		(layer "F.Cu")
		(at 356.53726 -327.09231 -90)
		(property "Reference" "PC99"
			(at 0 0 270)
			(layer "F.SilkS")
			(hide yes)
			(effects
				(font
					(size 1.27 1.27)
				)
			)
		)
		(property "Value" ""
			(at 0 0 270)
			(layer "F.Fab")
			(effects
				(font
					(size 1.27 1.27)
				)
			)
		)
		(duplicate_pad_numbers_are_jumpers no)
		(fp_line
			(start -0.7874 0.4064)
			(end -0.7874 -0.4064)
			(stroke
				(width 0.1524)
				(type default)
			)
			(layer "F.SilkS")
		)
		(fp_line
			(start 0.7874 0.4064)
			(end -0.7874 0.4064)
			(stroke
				(width 0.1524)
				(type default)
			)
			(layer "F.SilkS")
		)
		(fp_line
			(start -0.7874 -0.4064)
			(end 0.7874 -0.4064)
			(stroke
				(width 0.1524)
				(type default)
			)
			(layer "F.SilkS")
		)
		(fp_line
			(start 0.7874 -0.4064)
			(end 0.7874 0.4064)
			(stroke
				(width 0.1524)
				(type default)
			)
			(layer "F.SilkS")
		)
		(fp_line
			(start -0.67945 0.3048)
			(end -0.67945 -0.305054)
			(stroke
				(width 0.1)
				(type default)
			)
			(layer "F.Fab")
		)
		(fp_line
			(start -0.12065 0.3048)
			(end -0.67945 0.3048)
			(stroke
				(width 0.1)
				(type default)
			)
			(layer "F.Fab")
		)
		(fp_line
			(start 0.120396 0.3048)
			(end 0.120396 0.2794)
			(stroke
				(width 0.1)
				(type default)
			)
			(layer "F.Fab")
		)
		(fp_line
			(start 0.67945 0.3048)
			(end 0.120396 0.3048)
			(stroke
				(width 0.1)
				(type default)
			)
			(layer "F.Fab")
		)
		(fp_line
			(start -0.12065 0.2794)
			(end -0.12065 0.3048)
			(stroke
				(width 0.1)
				(type default)
			)
			(layer "F.Fab")
		)
		(fp_line
			(start 0.120396 0.2794)
			(end -0.12065 0.2794)
			(stroke
				(width 0.1)
				(type default)
			)
			(layer "F.Fab")
		)
		(fp_line
			(start -0.12065 -0.2794)
			(end 0.12065 -0.2794)
			(stroke
				(width 0.1)
				(type default)
			)
			(layer "F.Fab")
		)
		(fp_line
			(start 0.12065 -0.2794)
			(end 0.12065 -0.3048)
			(stroke
				(width 0.1)
				(type default)
			)
			(layer "F.Fab")
		)
		(fp_line
			(start 0.12065 -0.3048)
			(end 0.67945 -0.3048)
			(stroke
				(width 0.1)
				(type default)
			)
			(layer "F.Fab")
		)
		(fp_line
			(start 0.67945 -0.3048)
			(end 0.67945 0.3048)
			(stroke
				(width 0.1)
				(type default)
			)
			(layer "F.Fab")
		)
		(fp_line
			(start -0.67945 -0.305054)
			(end -0.12065 -0.305054)
			(stroke
				(width 0.1)
				(type default)
			)
			(layer "F.Fab")
		)
		(fp_line
			(start -0.12065 -0.305054)
			(end -0.12065 -0.2794)
			(stroke
				(width 0.1)
				(type default)
			)
			(layer "F.Fab")
		)
		(pad "1" smd circle
			(at -0.40005 0 270)
			(size 0 0)
			(layers "F.Cu" "F.Mask" "F.Paste")
			(net "PVDDCR_CPU1_P0")
		)
		(pad "2" smd circle
			(at 0.40005 0 270)
			(size 0 0)
			(layers "F.Cu" "F.Mask" "F.Paste")
			(net "GND")
		)
	)
)
